(kicad_pcb
	(version 20260206)
	(generator "pcbnew")
	(generator_version "10.0")
	(general
		(thickness 1.6)
		(legacy_teardrops no)
	)
	(paper "A4")
	(title_block
		(title "panther-plus-userver — 13130-1b_20150205.brd")
		(comment 1 "Honey Badger (Wiwynn) / footprints 640-646 of 1509")
	)
	(layers
		(0 "F.Cu" signal "TOP")
		(4 "In1.Cu" signal "L2")
		(6 "In2.Cu" signal "L3")
		(8 "In3.Cu" signal "L4")
		(10 "In4.Cu" signal "L5")
		(12 "In5.Cu" signal "L6")
		(14 "In6.Cu" signal "L7")
		(16 "In7.Cu" signal "L8")
		(18 "In8.Cu" signal "L9")
		(20 "In9.Cu" signal "L10")
		(22 "In10.Cu" signal "L11")
		(2 "B.Cu" signal "BOTTOM")
		(9 "F.Adhes" user "F.Adhesive")
		(11 "B.Adhes" user "B.Adhesive")
		(13 "F.Paste" user "Package Geometry/Pastemask Top")
		(15 "B.Paste" user "Package Geometry/Pastemask Bottom")
		(5 "F.SilkS" user "Ref Des/Silkscreen Top")
		(7 "B.SilkS" user "Ref Des/Silkscreen Bottom")
		(1 "F.Mask" user "Board Geometry/Soldermask Top")
		(3 "B.Mask" user "Board Geometry/Soldermask Bottom")
		(17 "Dwgs.User" user "User.Drawings")
		(19 "Cmts.User" user "User.Comments")
		(21 "Eco1.User" user "User.Eco1")
		(23 "Eco2.User" user "User.Eco2")
		(25 "Edge.Cuts" user "Board Geometry/Outline")
		(27 "Margin" user)
		(31 "F.CrtYd" user "Package Geometry/Place Bound Top")
		(29 "B.CrtYd" user "Package Geometry/Place Bound Bottom")
		(35 "F.Fab" user "Ref Des/Assembly Top")
		(33 "B.Fab" user "Ref Des/Assembly Bottom")
	)
	(footprint ""
		(layer "F.Cu")
		(at 17.018 -21.463)
		(property "Reference" "PR106"
			(at 0 0 0)
			(layer "F.SilkS")
			(hide yes)
			(effects
				(font
					(size 1.27 1.27)
				)
			)
		)
		(property "Value" "10KR2D-GP"
			(at 1.7907 -1.1176 0)
			(unlocked yes)
			(layer "F.Fab")
			(hide yes)
			(effects
				(font
					(size 1.016 1.016)
					(thickness 0.1524)
				)
			)
		)
		(property "Device Type" "R402H16"
			(at 1.7907 -2.6416 0)
			(unlocked yes)
			(layer "F.Fab")
			(hide yes)
			(effects
				(font
					(size 1.016 1.016)
					(thickness 0.1524)
				)
			)
		)
		(duplicate_pad_numbers_are_jumpers no)
		(fp_rect
			(start -0.381 0.8382)
			(end 0.381 -0.8382)
			(stroke
				(width 0)
				(type default)
			)
			(fill no)
			(layer "F.CrtYd")
		)
		(fp_rect
			(start -0.381 0.8382)
			(end 0.381 -0.8382)
			(stroke
				(width 0)
				(type default)
			)
			(fill no)
			(layer "F.Fab")
		)
		(pad "1" smd custom
			(at 0 -0.4318)
			(size 0.127 0.127)
			(layers "F.Cu" "F.Mask" "F.Paste")
			(net "P1V0_VFB")
			(options
				(clearance outline)
				(anchor circle)
			)
			(primitives
				(gr_poly
					(pts
						(arc
							(start -0.2032 -0.2794)
							(mid -0.239121 -0.264521)
							(end -0.254 -0.2286)
						)
						(arc
							(start -0.254 0.2286)
							(mid -0.239121 0.264521)
							(end -0.2032 0.2794)
						)
						(arc
							(start 0.2032 0.2794)
							(mid 0.239121 0.264521)
							(end 0.254 0.2286)
						)
						(arc
							(start 0.254 -0.2286)
							(mid 0.239121 -0.264521)
							(end 0.2032 -0.2794)
						)
					)
					(width 0)
					(fill yes)
				)
			)
		)
		(pad "2" smd custom
			(at 0 0.4318)
			(size 0.127 0.127)
			(layers "F.Cu" "F.Mask" "F.Paste")
			(net "AGND_P1V0")
			(options
				(clearance outline)
				(anchor circle)
			)
			(primitives
				(gr_poly
					(pts
						(arc
							(start -0.2032 -0.2794)
							(mid -0.239121 -0.264521)
							(end -0.254 -0.2286)
						)
						(arc
							(start -0.254 0.2286)
							(mid -0.239121 0.264521)
							(end -0.2032 0.2794)
						)
						(arc
							(start 0.2032 0.2794)
							(mid 0.239121 0.264521)
							(end 0.254 0.2286)
						)
						(arc
							(start 0.254 -0.2286)
							(mid 0.239121 -0.264521)
							(end 0.2032 -0.2794)
						)
					)
					(width 0)
					(fill yes)
				)
			)
		)
	)
	(footprint ""
		(layer "F.Cu")
		(at 203.962 -67.4624 90)
		(property "Reference" "PC179"
			(at 0 0 90)
			(layer "F.SilkS")
			(hide yes)
			(effects
				(font
					(size 1.27 1.27)
				)
			)
		)
		(property "Value" "SC10U6D3V3MX-GP"
			(at -0.0254 -2.0193 90)
			(unlocked yes)
			(layer "F.Fab")
			(hide yes)
			(effects
				(font
					(size 1.016 1.016)
					(thickness 0.1524)
				)
			)
		)
		(property "Device Type" "C603H38"
			(at -0.0254 -3.5433 90)
			(unlocked yes)
			(layer "F.Fab")
			(hide yes)
			(effects
				(font
					(size 1.016 1.016)
					(thickness 0.1524)
				)
			)
		)
		(duplicate_pad_numbers_are_jumpers no)
		(fp_line
			(start -0.4064 0)
			(end 0.4064 0)
			(stroke
				(width 0.2286)
				(type default)
			)
			(layer "F.SilkS")
		)
		(fp_rect
			(start -0.635 1.1811)
			(end 0.635 -1.1811)
			(stroke
				(width 0)
				(type default)
			)
			(fill no)
			(layer "F.CrtYd")
		)
		(fp_rect
			(start -0.635 1.1811)
			(end 0.635 -1.1811)
			(stroke
				(width 0)
				(type default)
			)
			(fill no)
			(layer "F.Fab")
		)
		(pad "1" smd custom
			(at 0 -0.6604 90)
			(size 0.19685 0.19685)
			(layers "F.Cu" "F.Mask" "F.Paste")
			(net "PV_VDDR")
			(options
				(clearance outline)
				(anchor circle)
			)
			(primitives
				(gr_poly
					(pts
						(arc
							(start 0.508 -0.2921)
							(mid 0.478242 -0.363942)
							(end 0.4064 -0.3937)
						)
						(arc
							(start -0.4064 -0.3937)
							(mid -0.478242 -0.363942)
							(end -0.508 -0.2921)
						)
						(arc
							(start -0.508 0.2921)
							(mid -0.478242 0.363942)
							(end -0.4064 0.3937)
						)
						(arc
							(start 0.4064 0.3937)
							(mid 0.478242 0.363942)
							(end 0.508 0.2921)
						)
					)
					(width 0)
					(fill yes)
				)
			)
		)
		(pad "2" smd custom
			(at 0 0.6604 90)
			(size 0.19685 0.19685)
			(layers "F.Cu" "F.Mask" "F.Paste")
			(net "GND")
			(options
				(clearance outline)
				(anchor circle)
			)
			(primitives
				(gr_poly
					(pts
						(arc
							(start 0.508 -0.2921)
							(mid 0.478242 -0.363942)
							(end 0.4064 -0.3937)
						)
						(arc
							(start -0.4064 -0.3937)
							(mid -0.478242 -0.363942)
							(end -0.508 -0.2921)
						)
						(arc
							(start -0.508 0.2921)
							(mid -0.478242 0.363942)
							(end -0.4064 0.3937)
						)
						(arc
							(start 0.4064 0.3937)
							(mid 0.478242 0.363942)
							(end 0.508 0.2921)
						)
					)
					(width 0)
					(fill yes)
				)
			)
		)
	)
	(footprint ""
		(layer "F.Cu")
		(at 74.041 -29.972 90)
		(property "Reference" "R117"
			(at 0 0 90)
			(layer "F.SilkS")
			(hide yes)
			(effects
				(font
					(size 1.27 1.27)
				)
			)
		)
		(property "Value" "10KR2F-2-GP"
			(at 0.064008 -3.993896 90)
			(unlocked yes)
			(layer "F.Fab")
			(hide yes)
			(effects
				(font
					(size 1.016 1.016)
					(thickness 0.1524)
				)
			)
		)
		(property "Device Type" "R402H16"
			(at 0.064008 -5.517896 90)
			(unlocked yes)
			(layer "F.Fab")
			(hide yes)
			(effects
				(font
					(size 1.016 1.016)
					(thickness 0.1524)
				)
			)
		)
		(duplicate_pad_numbers_are_jumpers no)
		(fp_rect
			(start -0.381 0.8382)
			(end 0.381 -0.8382)
			(stroke
				(width 0)
				(type default)
			)
			(fill no)
			(layer "F.CrtYd")
		)
		(fp_rect
			(start -0.381 0.8382)
			(end 0.381 -0.8382)
			(stroke
				(width 0)
				(type default)
			)
			(fill no)
			(layer "F.Fab")
		)
		(pad "1" smd custom
			(at 0 -0.4318 90)
			(size 0.127 0.127)
			(layers "F.Cu" "F.Mask" "F.Paste")
			(net "P3V3_CPU")
			(options
				(clearance outline)
				(anchor circle)
			)
			(primitives
				(gr_poly
					(pts
						(arc
							(start -0.2032 -0.2794)
							(mid -0.239121 -0.264521)
							(end -0.254 -0.2286)
						)
						(arc
							(start -0.254 0.2286)
							(mid -0.239121 0.264521)
							(end -0.2032 0.2794)
						)
						(arc
							(start 0.2032 0.2794)
							(mid 0.239121 0.264521)
							(end 0.254 0.2286)
						)
						(arc
							(start 0.254 -0.2286)
							(mid 0.239121 -0.264521)
							(end 0.2032 -0.2794)
						)
					)
					(width 0)
					(fill yes)
				)
			)
		)
		(pad "2" smd custom
			(at 0 0.4318 90)
			(size 0.127 0.127)
			(layers "F.Cu" "F.Mask" "F.Paste")
			(net "PMU_SLP_S45#")
			(options
				(clearance outline)
				(anchor circle)
			)
			(primitives
				(gr_poly
					(pts
						(arc
							(start -0.2032 -0.2794)
							(mid -0.239121 -0.264521)
							(end -0.254 -0.2286)
						)
						(arc
							(start -0.254 0.2286)
							(mid -0.239121 0.264521)
							(end -0.2032 0.2794)
						)
						(arc
							(start 0.2032 0.2794)
							(mid 0.239121 0.264521)
							(end 0.254 0.2286)
						)
						(arc
							(start 0.254 -0.2286)
							(mid 0.239121 -0.264521)
							(end 0.2032 -0.2794)
						)
					)
					(width 0)
					(fill yes)
				)
			)
		)
	)
	(footprint ""
		(layer "F.Cu")
		(at 175.006 -51.816 180)
		(property "Reference" "U22"
			(at 0 0 180)
			(layer "F.SilkS")
			(hide yes)
			(effects
				(font
					(size 1.27 1.27)
				)
			)
		)
		(property "Value" "M24128-BWMN6TP-GP"
			(at 4.064 -7.5692 180)
			(unlocked yes)
			(layer "F.Fab")
			(hide yes)
			(effects
				(font
					(size 1.016 1.016)
					(thickness 0.1524)
				)
			)
		)
		(property "Device Type" "SOIC8H69"
			(at 4.064 -6.0452 180)
			(unlocked yes)
			(layer "F.Fab")
			(hide yes)
			(effects
				(font
					(size 1.016 1.016)
					(thickness 0.1524)
				)
			)
		)
		(duplicate_pad_numbers_are_jumpers no)
		(fp_line
			(start 2.1463 1.4351)
			(end 2.1463 -1.4351)
			(stroke
				(width 0.1524)
				(type default)
			)
			(layer "F.SilkS")
		)
		(fp_line
			(start 2.1463 -1.4351)
			(end -2.6797 -1.4351)
			(stroke
				(width 0.1524)
				(type default)
			)
			(layer "F.SilkS")
		)
		(fp_line
			(start -2.1717 0)
			(end -2.6797 -0.508)
			(stroke
				(width 0.1524)
				(type default)
			)
			(layer "F.SilkS")
		)
		(fp_line
			(start -2.502154 1.4224)
			(end -2.502154 3.1115)
			(stroke
				(width 0.508)
				(type default)
			)
			(layer "F.SilkS")
		)
		(fp_line
			(start -2.6797 1.4351)
			(end 2.1463 1.4351)
			(stroke
				(width 0.1524)
				(type default)
			)
			(layer "F.SilkS")
		)
		(fp_line
			(start -2.6797 0.508)
			(end -2.1717 0)
			(stroke
				(width 0.1524)
				(type default)
			)
			(layer "F.SilkS")
		)
		(fp_line
			(start -2.6797 -0.508)
			(end -2.6797 0.508)
			(stroke
				(width 0.1524)
				(type default)
			)
			(layer "F.SilkS")
		)
		(fp_line
			(start -2.6797 -1.4351)
			(end -2.6797 1.4351)
			(stroke
				(width 0.1524)
				(type default)
			)
			(layer "F.SilkS")
		)
		(fp_poly
			(pts
				(xy -2.2225 -1.4351) (xy -2.2225 1.4351) (xy 2.1463 1.4351) (xy 2.1463 -1.4351)
			)
			(stroke
				(width 0)
				(type default)
			)
			(fill yes)
			(layer "F.SilkS")
		)
		(fp_rect
			(start -2.7559 3.3655)
			(end 2.7559 -3.3655)
			(stroke
				(width 0)
				(type default)
			)
			(fill no)
			(layer "F.CrtYd")
		)
		(fp_rect
			(start -2.7559 3.3655)
			(end 2.7559 -3.3655)
			(stroke
				(width 0)
				(type default)
			)
			(fill no)
			(layer "F.Fab")
		)
		(pad "1" smd rect
			(at -1.905 2.4765 180)
			(size 0.635 1.524)
			(layers "F.Cu" "F.Mask" "F.Paste")
			(net "EEPROM_A0")
		)
		(pad "2" smd rect
			(at -0.635 2.4765 180)
			(size 0.635 1.524)
			(layers "F.Cu" "F.Mask" "F.Paste")
			(net "EEPROM_A1")
		)
		(pad "3" smd rect
			(at 0.635 2.4765 180)
			(size 0.635 1.524)
			(layers "F.Cu" "F.Mask" "F.Paste")
			(net "EEPROM_A2")
		)
		(pad "4" smd rect
			(at 1.905 2.4765 180)
			(size 0.635 1.524)
			(layers "F.Cu" "F.Mask" "F.Paste")
			(net "GND")
		)
		(pad "5" smd rect
			(at 1.905 -2.4765 180)
			(size 0.635 1.524)
			(layers "F.Cu" "F.Mask" "F.Paste")
			(net "EEPROM_DATA")
		)
		(pad "6" smd rect
			(at 0.635 -2.4765 180)
			(size 0.635 1.524)
			(layers "F.Cu" "F.Mask" "F.Paste")
			(net "EEPROM_CLK")
		)
		(pad "7" smd rect
			(at -0.635 -2.4765 180)
			(size 0.635 1.524)
			(layers "F.Cu" "F.Mask" "F.Paste")
			(net "EEPROM_WP")
		)
		(pad "8" smd rect
			(at -1.905 -2.4765 180)
			(size 0.635 1.524)
			(layers "F.Cu" "F.Mask" "F.Paste")
			(net "P3V3_STBY")
		)
	)
	(footprint ""
		(layer "F.Cu")
		(at 111.631984 -58.944002 90)
		(property "Reference" "R22"
			(at 0 0 90)
			(layer "F.SilkS")
			(hide yes)
			(effects
				(font
					(size 1.27 1.27)
				)
			)
		)
		(property "Value" "100R3F-1-GP"
			(at -0.0254 -2.5146 90)
			(unlocked yes)
			(layer "F.Fab")
			(hide yes)
			(effects
				(font
					(size 1.016 1.016)
					(thickness 0.1524)
				)
			)
		)
		(property "Device Type" "R603H22"
			(at -0.0254 -4.0386 90)
			(unlocked yes)
			(layer "F.Fab")
			(hide yes)
			(effects
				(font
					(size 1.016 1.016)
					(thickness 0.1524)
				)
			)
		)
		(duplicate_pad_numbers_are_jumpers no)
		(fp_line
			(start 0.4318 0)
			(end 0.2032 0)
			(stroke
				(width 0.2032)
				(type default)
			)
			(layer "F.SilkS")
		)
		(fp_line
			(start -0.2032 0)
			(end -0.4191 0)
			(stroke
				(width 0.2032)
				(type default)
			)
			(layer "F.SilkS")
		)
		(fp_rect
			(start -0.635 1.1811)
			(end 0.635 -1.1811)
			(stroke
				(width 0)
				(type default)
			)
			(fill no)
			(layer "F.CrtYd")
		)
		(fp_rect
			(start -0.635 1.1811)
			(end 0.635 -1.1811)
			(stroke
				(width 0)
				(type default)
			)
			(fill no)
			(layer "F.Fab")
		)
		(pad "1" smd custom
			(at 0 -0.6604 90)
			(size 0.19685 0.19685)
			(layers "F.Cu" "F.Mask" "F.Paste")
			(net "M_A_MON2_P")
			(options
				(clearance outline)
				(anchor circle)
			)
			(primitives
				(gr_poly
					(pts
						(arc
							(start 0.508 -0.2921)
							(mid 0.478242 -0.363942)
							(end 0.4064 -0.3937)
						)
						(arc
							(start -0.4064 -0.3937)
							(mid -0.478242 -0.363942)
							(end -0.508 -0.2921)
						)
						(arc
							(start -0.508 0.2921)
							(mid -0.478242 0.363942)
							(end -0.4064 0.3937)
						)
						(arc
							(start 0.4064 0.3937)
							(mid 0.478242 0.363942)
							(end 0.508 0.2921)
						)
					)
					(width 0)
					(fill yes)
				)
			)
		)
		(pad "2" smd custom
			(at 0 0.6604 90)
			(size 0.19685 0.19685)
			(layers "F.Cu" "F.Mask" "F.Paste")
			(net "M_A_MON2_N")
			(options
				(clearance outline)
				(anchor circle)
			)
			(primitives
				(gr_poly
					(pts
						(arc
							(start 0.508 -0.2921)
							(mid 0.478242 -0.363942)
							(end 0.4064 -0.3937)
						)
						(arc
							(start -0.4064 -0.3937)
							(mid -0.478242 -0.363942)
							(end -0.508 -0.2921)
						)
						(arc
							(start -0.508 0.2921)
							(mid -0.478242 0.363942)
							(end -0.4064 0.3937)
						)
						(arc
							(start 0.4064 0.3937)
							(mid 0.478242 0.363942)
							(end 0.508 0.2921)
						)
					)
					(width 0)
					(fill yes)
				)
			)
		)
	)
	(footprint ""
		(layer "F.Cu")
		(at 53.34 -53.467 -90)
		(property "Reference" "PG4"
			(at 0 0 270)
			(layer "F.SilkS")
			(hide yes)
			(effects
				(font
					(size 1.27 1.27)
				)
			)
		)
		(property "Value" "COPPER-CLOSE-GP-U"
			(at 0.0762 -2.8702 270)
			(unlocked yes)
			(layer "F.Fab")
			(hide yes)
			(effects
				(font
					(size 1.016 1.016)
					(thickness 0.1524)
				)
			)
		)
		(property "Device Type" "CON2C-U"
			(at 0.0762 -4.3942 270)
			(unlocked yes)
			(layer "F.Fab")
			(hide yes)
			(effects
				(font
					(size 1.016 1.016)
					(thickness 0.1524)
				)
			)
		)
		(duplicate_pad_numbers_are_jumpers no)
		(fp_rect
			(start -0.9398 0.9652)
			(end 0.9398 -0.9652)
			(stroke
				(width 0)
				(type default)
			)
			(fill no)
			(layer "F.CrtYd")
		)
		(fp_rect
			(start -0.9398 0.9652)
			(end 0.9398 -0.9652)
			(stroke
				(width 0)
				(type default)
			)
			(fill no)
			(layer "F.Fab")
		)
		(pad "1" smd custom
			(at 0 -0.5334 270)
			(size 0.17145 0.17145)
			(layers "F.Cu" "F.Mask" "F.Paste")
			(net "AGND_P1V0_STBY")
			(options
				(clearance outline)
				(anchor circle)
			)
			(primitives
				(gr_poly
					(pts
						(xy -0.127 0.3429) (xy -0.127 0.1651) (xy -0.635 -0.3429) (xy 0.635 -0.3429) (xy 0.127 0.1651)
						(xy 0.127 0.3429)
					)
					(width 0)
					(fill yes)
				)
			)
		)
		(pad "2" smd custom
			(at 0 0.5334 270)
			(size 0.17145 0.17145)
			(layers "F.Cu" "F.Mask" "F.Paste")
			(net "GND")
			(options
				(clearance outline)
				(anchor circle)
			)
			(primitives
				(gr_poly
					(pts
						(xy -0.635 0.3429) (xy -0.127 -0.1651) (xy -0.127 -0.3429) (xy 0.127 -0.3429) (xy 0.127 -0.1651)
						(xy 0.635 0.3429)
					)
					(width 0)
					(fill yes)
				)
			)
		)
	)
	(footprint ""
		(layer "F.Cu")
		(at 188.976 -41.529 180)
		(property "Reference" "PR115"
			(at 0 0 180)
			(layer "F.SilkS")
			(hide yes)
			(effects
				(font
					(size 1.27 1.27)
				)
			)
		)
		(property "Value" "10KR2F-2-GP"
			(at 1.7907 -1.1176 180)
			(unlocked yes)
			(layer "F.Fab")
			(hide yes)
			(effects
				(font
					(size 1.016 1.016)
					(thickness 0.1524)
				)
			)
		)
		(property "Device Type" "R402H16"
			(at 1.7907 -2.6416 180)
			(unlocked yes)
			(layer "F.Fab")
			(hide yes)
			(effects
				(font
					(size 1.016 1.016)
					(thickness 0.1524)
				)
			)
		)
		(duplicate_pad_numbers_are_jumpers no)
		(fp_rect
			(start -0.381 0.8382)
			(end 0.381 -0.8382)
			(stroke
				(width 0)
				(type default)
			)
			(fill no)
			(layer "F.CrtYd")
		)
		(fp_rect
			(start -0.381 0.8382)
			(end 0.381 -0.8382)
			(stroke
				(width 0)
				(type default)
			)
			(fill no)
			(layer "F.Fab")
		)
		(pad "1" smd custom
			(at 0 -0.4318 180)
			(size 0.127 0.127)
			(layers "F.Cu" "F.Mask" "F.Paste")
			(net "VR_PVDDR_A_VAUTO")
			(options
				(clearance outline)
				(anchor circle)
			)
			(primitives
				(gr_poly
					(pts
						(arc
							(start -0.2032 -0.2794)
							(mid -0.239121 -0.264521)
							(end -0.254 -0.2286)
						)
						(arc
							(start -0.254 0.2286)
							(mid -0.239121 0.264521)
							(end -0.2032 0.2794)
						)
						(arc
							(start 0.2032 0.2794)
							(mid 0.239121 0.264521)
							(end 0.254 0.2286)
						)
						(arc
							(start 0.254 -0.2286)
							(mid 0.239121 -0.264521)
							(end 0.2032 -0.2794)
						)
					)
					(width 0)
					(fill yes)
				)
			)
		)
		(pad "2" smd custom
			(at 0 0.4318 180)
			(size 0.127 0.127)
			(layers "F.Cu" "F.Mask" "F.Paste")
			(net "PV_VDDR")
			(options
				(clearance outline)
				(anchor circle)
			)
			(primitives
				(gr_poly
					(pts
						(arc
							(start -0.2032 -0.2794)
							(mid -0.239121 -0.264521)
							(end -0.254 -0.2286)
						)
						(arc
							(start -0.254 0.2286)
							(mid -0.239121 0.264521)
							(end -0.2032 0.2794)
						)
						(arc
							(start 0.2032 0.2794)
							(mid 0.239121 0.264521)
							(end 0.254 0.2286)
						)
						(arc
							(start 0.254 -0.2286)
							(mid 0.239121 -0.264521)
							(end 0.2032 -0.2794)
						)
					)
					(width 0)
					(fill yes)
				)
			)
		)
	)
)
